#ISCELL
  mstr_misc dns *
  *
#ISCELL
  mstr_symbols cad_note *
  *
#ISCELL
  mstr_symbols intel_corp_bpage *
  *
#CELL
  mstr_conn conn6_c74770005 *
  page161_i1
#ISCELL
  mstr_standard offpage *
  page161_i100
#CELL
  mstr_discrete res *
  page161_i102
#ISCELL
  mstr_standard offpage *
  page161_i103
#ISCELL
  mstr_symbols gnd *
  page161_i104
#ISCELL
  mstr_symbols p3v3_stby *
  page161_i105
#ISCELL
  mstr_symbols p12v_fan *
  page161_i108
#ISCELL
  mstr_symbols p12v_fan *
  page161_i110
#ISCELL
  mstr_symbols gnd *
  page161_i111
#CELL
  dev_discrete cap_a *
  page161_i113
#ISCELL
  mstr_standard offpage *
  page161_i114
#ISCELL
  mstr_standard offpage *
  page161_i115
#ISCELL
  mstr_standard offpage *
  page161_i116
#ISCELL
  mstr_symbols p3v3_stby *
  page161_i117
#ISCELL
  mstr_symbols gnd *
  page161_i118
#ISCELL
  mstr_symbols p3v3_stby *
  page161_i119
#CELL
  mstr_discrete res *
  page161_i120
#CELL
  mstr_ttl ttl1g08 *
  page161_i121
#ISCELL
  mstr_symbols gnd *
  page161_i122
#CELL
  mstr_discrete diode *
  page161_i123
#CELL
  mstr_discrete res *
  page161_i124
#CELL
  mstr_discrete res *
  page161_i126
#CELL
  dev_discrete cap_a *
  page161_i128
#ISCELL
  mstr_symbols gnd *
  page161_i129
#ISCELL
  mstr_symbols gnd *
  page161_i13
#ISCELL
  mstr_symbols p3v3_stby *
  page161_i130
#ISCELL
  mstr_standard offpage *
  page161_i131
#ISCELL
  mstr_symbols gnd *
  page161_i132
#CELL
  mstr_discrete diode *
  page161_i133
#CELL
  mstr_discrete res *
  page161_i134
#CELL
  mstr_discrete res *
  page161_i135
#ISCELL
  mstr_symbols p3v3_stby *
  page161_i136
#CELL
  dev_discrete cap_a *
  page161_i137
#ISCELL
  mstr_standard offpage *
  page161_i138
#CELL
  dev_discrete cap_a *
  page161_i26
#CELL
  mstr_discrete cap *
  page161_i27
#CELL
  mstr_discrete cap *
  page161_i3
#ISCELL
  mstr_symbols gnd *
  page161_i30
#CELL
  mstr_conn conn6_c74770005 *
  page161_i32
#CELL
  dev_discrete cap_a *
  page161_i4
#CELL
  mstr_discrete diode *
  page161_i42
#CELL
  mstr_discrete res *
  page161_i43
#CELL
  mstr_discrete res *
  page161_i45
#CELL
  dev_discrete cap_a *
  page161_i46
#ISCELL
  mstr_symbols gnd *
  page161_i47
#ISCELL
  mstr_symbols p3v3_stby *
  page161_i48
#ISCELL
  mstr_standard offpage *
  page161_i49
#CELL
  mstr_discrete diode *
  page161_i50
#CELL
  mstr_discrete res *
  page161_i51
#ISCELL
  mstr_symbols p5v_stby *
  page161_i52
#ISCELL
  mstr_standard offpage *
  page161_i53
#ISCELL
  mstr_symbols p3v3_stby *
  page161_i61
#CELL
  mstr_discrete diode *
  page161_i62
#ISCELL
  mstr_symbols p5v_stby *
  page161_i63
#CELL
  mstr_discrete diode *
  page161_i64
#CELL
  mstr_discrete res *
  page161_i65
#CELL
  mstr_discrete res *
  page161_i67
#CELL
  dev_discrete cap_a *
  page161_i68
#ISCELL
  mstr_symbols gnd *
  page161_i69
#CELL
  mstr_discrete res *
  page161_i70
#ISCELL
  mstr_standard offpage *
  page161_i75
#ISCELL
  mstr_standard offpage *
  page161_i76
#CELL
  mstr_ttl ttl1g07_a *
  page161_i88
#CELL
  dev_discrete cap_a *
  page161_i90
#CELL
  mstr_ttl ttl1g07_a *
  page161_i92
#CELL
  dev_discrete cap_a *
  page161_i93
#ISCELL
  mstr_standard offpage *
  page161_i94
#ISCELL
  mstr_symbols p3v3_stby *
  page161_i96
#ISCELL
  mstr_symbols gnd *
  page161_i97
#ISCELL
  mstr_standard offpage *
  page161_i98
#CELL
  mstr_discrete res *
  page161_i99
